(kicad_pcb
	(version 20260206)
	(generator "pcbnew")
	(generator_version "10.0")
	(general
		(thickness 1.6)
		(legacy_teardrops no)
	)
	(paper "A4")
	(title_block
		(title "peb — Lightning_PEB_BRD.brd")
		(comment 1 "Lightning (Wiwynn / Facebook NVMe JBOF) / footprints 2484-2490 of 2563")
	)
	(layers
		(0 "F.Cu" signal "TOP")
		(4 "In1.Cu" signal "L2GND")
		(6 "In2.Cu" signal "L3")
		(8 "In3.Cu" signal "L4VCC")
		(10 "In4.Cu" signal "L5VCC")
		(12 "In5.Cu" signal "L6")
		(14 "In6.Cu" signal "L7GND")
		(2 "B.Cu" signal "BOTTOM")
		(9 "F.Adhes" user "F.Adhesive")
		(11 "B.Adhes" user "B.Adhesive")
		(13 "F.Paste" user "Package Geometry/Pastemask Top")
		(15 "B.Paste" user "Package Geometry/Pastemask Bottom")
		(5 "F.SilkS" user "Ref Des/Silkscreen Top")
		(7 "B.SilkS" user "Ref Des/Silkscreen Bottom")
		(1 "F.Mask" user "Board Geometry/Soldermask Top")
		(3 "B.Mask" user "Board Geometry/Soldermask Bottom")
		(17 "Dwgs.User" user "User.Drawings")
		(19 "Cmts.User" user "User.Comments")
		(21 "Eco1.User" user "User.Eco1")
		(23 "Eco2.User" user "User.Eco2")
		(25 "Edge.Cuts" user "Board Geometry/Outline")
		(27 "Margin" user)
		(31 "F.CrtYd" user "Package Geometry/Place Bound Top")
		(29 "B.CrtYd" user "Package Geometry/Place Bound Bottom")
		(35 "F.Fab" user "Ref Des/Assembly Top")
		(33 "B.Fab" user "Ref Des/Assembly Bottom")
	)
	(footprint ""
		(layer "B.Cu")
		(at 241.599974 -38.999922 90)
		(property "Reference" "TP192"
			(at 0 0 90)
			(layer "B.SilkS")
			(hide yes)
			(effects
				(font
					(size 1.27 1.27)
				)
				(justify mirror)
			)
		)
		(property "Value" "TPAD28-2-GP"
			(at 0.0127 -1.6637 90)
			(unlocked yes)
			(layer "B.Fab")
			(hide yes)
			(effects
				(font
					(size 1.016 1.016)
					(thickness 0.1524)
				)
				(justify mirror)
			)
		)
		(property "Device Type" "TPAD28"
			(at 0.0127 -3.1877 90)
			(unlocked yes)
			(layer "B.Fab")
			(hide yes)
			(effects
				(font
					(size 1.016 1.016)
					(thickness 0.1524)
				)
				(justify mirror)
			)
		)
		(duplicate_pad_numbers_are_jumpers no)
		(fp_poly
			(pts
				(arc
					(start 0 0.3556)
					(mid 0 -0.3556)
					(end 0 0.3556)
				)
			)
			(stroke
				(width 0)
				(type default)
			)
			(fill no)
			(layer "B.CrtYd")
		)
		(fp_poly
			(pts
				(arc
					(start 0 0.6096)
					(mid 0 -0.6096)
					(end 0 0.6096)
				)
			)
			(stroke
				(width 0)
				(type default)
			)
			(fill no)
			(layer "B.Fab")
		)
		(pad "1" smd circle
			(at 0 0 270)
			(size 0.7112 0.7112)
			(layers "B.Cu" "B.Mask" "B.Paste")
			(net "LBI_WE#")
		)
	)
	(footprint ""
		(layer "B.Cu")
		(at 220.5736 -194.5132 90)
		(property "Reference" "R3212"
			(at 0 0 90)
			(layer "B.SilkS")
			(hide yes)
			(effects
				(font
					(size 1.27 1.27)
				)
				(justify mirror)
			)
		)
		(property "Value" "0R2J-2-GP"
			(at -0.064008 -3.993896 90)
			(unlocked yes)
			(layer "B.Fab")
			(hide yes)
			(effects
				(font
					(size 1.016 1.016)
					(thickness 0.1524)
				)
				(justify mirror)
			)
		)
		(property "Device Type" "R402H16"
			(at -0.064008 -5.517896 90)
			(unlocked yes)
			(layer "B.Fab")
			(hide yes)
			(effects
				(font
					(size 1.016 1.016)
					(thickness 0.1524)
				)
				(justify mirror)
			)
		)
		(duplicate_pad_numbers_are_jumpers no)
		(fp_line
			(start 0.508 -0.9398)
			(end 0.508 0.9398)
			(stroke
				(width 0.1524)
				(type default)
			)
			(layer "B.SilkS")
		)
		(fp_line
			(start -0.508 -0.9398)
			(end 0.508 -0.9398)
			(stroke
				(width 0.1524)
				(type default)
			)
			(layer "B.SilkS")
		)
		(fp_rect
			(start 0.508 0.9398)
			(end -0.508 -0.9398)
			(stroke
				(width 0)
				(type default)
			)
			(fill no)
			(layer "B.CrtYd")
		)
		(fp_rect
			(start 0.508 0.9398)
			(end -0.508 -0.9398)
			(stroke
				(width 0)
				(type default)
			)
			(fill no)
			(layer "B.Fab")
		)
		(pad "1" smd custom
			(at 0 -0.4445 270)
			(size 0.1397 0.1397)
			(layers "B.Cu" "B.Mask" "B.Paste")
			(net "SSD_PERST_Y3")
			(options
				(clearance outline)
				(anchor circle)
			)
			(primitives
				(gr_poly
					(pts
						(arc
							(start -0.1778 0.2794)
							(mid -0.249642 0.249642)
							(end -0.2794 0.1778)
						)
						(arc
							(start -0.2794 -0.1778)
							(mid -0.249642 -0.249642)
							(end -0.1778 -0.2794)
						)
						(arc
							(start 0.1778 -0.2794)
							(mid 0.249642 -0.249642)
							(end 0.2794 -0.1778)
						)
						(arc
							(start 0.2794 0.1778)
							(mid 0.249642 0.249642)
							(end 0.1778 0.2794)
						)
					)
					(width 0)
					(fill yes)
				)
			)
		)
		(pad "2" smd custom
			(at 0 0.4445 270)
			(size 0.1397 0.1397)
			(layers "B.Cu" "B.Mask" "B.Paste")
			(net "SSD_PERST#3_R")
			(options
				(clearance outline)
				(anchor circle)
			)
			(primitives
				(gr_poly
					(pts
						(arc
							(start -0.1778 0.2794)
							(mid -0.249642 0.249642)
							(end -0.2794 0.1778)
						)
						(arc
							(start -0.2794 -0.1778)
							(mid -0.249642 -0.249642)
							(end -0.1778 -0.2794)
						)
						(arc
							(start 0.1778 -0.2794)
							(mid 0.249642 -0.249642)
							(end 0.2794 -0.1778)
						)
						(arc
							(start 0.2794 0.1778)
							(mid 0.249642 0.249642)
							(end 0.1778 0.2794)
						)
					)
					(width 0)
					(fill yes)
				)
			)
		)
	)
	(footprint ""
		(layer "B.Cu")
		(at 339.884512 -172.432218)
		(property "Reference" "R4161"
			(at 0 0 0)
			(layer "B.SilkS")
			(hide yes)
			(effects
				(font
					(size 1.27 1.27)
				)
				(justify mirror)
			)
		)
		(property "Value" "4K7R2F-GP"
			(at -0.064008 -3.993896 0)
			(unlocked yes)
			(layer "B.Fab")
			(hide yes)
			(effects
				(font
					(size 1.016 1.016)
					(thickness 0.1524)
				)
				(justify mirror)
			)
		)
		(property "Device Type" "R402H16"
			(at -0.064008 -5.517896 0)
			(unlocked yes)
			(layer "B.Fab")
			(hide yes)
			(effects
				(font
					(size 1.016 1.016)
					(thickness 0.1524)
				)
				(justify mirror)
			)
		)
		(duplicate_pad_numbers_are_jumpers no)
		(fp_line
			(start -0.508 -0.9398)
			(end 0.508 -0.9398)
			(stroke
				(width 0.1524)
				(type default)
			)
			(layer "B.SilkS")
		)
		(fp_line
			(start 0.508 -0.9398)
			(end 0.508 0.9398)
			(stroke
				(width 0.1524)
				(type default)
			)
			(layer "B.SilkS")
		)
		(fp_rect
			(start 0.508 0.9398)
			(end -0.508 -0.9398)
			(stroke
				(width 0)
				(type default)
			)
			(fill no)
			(layer "B.CrtYd")
		)
		(fp_rect
			(start 0.508 0.9398)
			(end -0.508 -0.9398)
			(stroke
				(width 0)
				(type default)
			)
			(fill no)
			(layer "B.Fab")
		)
		(pad "1" smd custom
			(at 0 -0.4445 180)
			(size 0.1397 0.1397)
			(layers "B.Cu" "B.Mask" "B.Paste")
			(net "SSD_PERST#9")
			(options
				(clearance outline)
				(anchor circle)
			)
			(primitives
				(gr_poly
					(pts
						(arc
							(start -0.1778 0.2794)
							(mid -0.249642 0.249642)
							(end -0.2794 0.1778)
						)
						(arc
							(start -0.2794 -0.1778)
							(mid -0.249642 -0.249642)
							(end -0.1778 -0.2794)
						)
						(arc
							(start 0.1778 -0.2794)
							(mid 0.249642 -0.249642)
							(end 0.2794 -0.1778)
						)
						(arc
							(start 0.2794 0.1778)
							(mid 0.249642 0.249642)
							(end 0.1778 0.2794)
						)
					)
					(width 0)
					(fill yes)
				)
			)
		)
		(pad "2" smd custom
			(at 0 0.4445 180)
			(size 0.1397 0.1397)
			(layers "B.Cu" "B.Mask" "B.Paste")
			(net "P3V3_STBY")
			(options
				(clearance outline)
				(anchor circle)
			)
			(primitives
				(gr_poly
					(pts
						(arc
							(start -0.1778 0.2794)
							(mid -0.249642 0.249642)
							(end -0.2794 0.1778)
						)
						(arc
							(start -0.2794 -0.1778)
							(mid -0.249642 -0.249642)
							(end -0.1778 -0.2794)
						)
						(arc
							(start 0.1778 -0.2794)
							(mid 0.249642 -0.249642)
							(end 0.2794 -0.1778)
						)
						(arc
							(start 0.2794 0.1778)
							(mid 0.249642 0.249642)
							(end 0.1778 0.2794)
						)
					)
					(width 0)
					(fill yes)
				)
			)
		)
	)
	(footprint ""
		(layer "B.Cu")
		(at 51.5366 -128.7272 90)
		(property "Reference" "R530"
			(at 0 0 90)
			(layer "B.SilkS")
			(hide yes)
			(effects
				(font
					(size 1.27 1.27)
				)
				(justify mirror)
			)
		)
		(property "Value" "0R2J-2-GP"
			(at -0.064008 -3.993896 90)
			(unlocked yes)
			(layer "B.Fab")
			(hide yes)
			(effects
				(font
					(size 1.016 1.016)
					(thickness 0.1524)
				)
				(justify mirror)
			)
		)
		(property "Device Type" "R402H16"
			(at -0.064008 -5.517896 90)
			(unlocked yes)
			(layer "B.Fab")
			(hide yes)
			(effects
				(font
					(size 1.016 1.016)
					(thickness 0.1524)
				)
				(justify mirror)
			)
		)
		(duplicate_pad_numbers_are_jumpers no)
		(fp_line
			(start 0.508 -0.9398)
			(end 0.508 0.9398)
			(stroke
				(width 0.1524)
				(type default)
			)
			(layer "B.SilkS")
		)
		(fp_line
			(start -0.508 -0.9398)
			(end 0.508 -0.9398)
			(stroke
				(width 0.1524)
				(type default)
			)
			(layer "B.SilkS")
		)
		(fp_rect
			(start 0.508 0.9398)
			(end -0.508 -0.9398)
			(stroke
				(width 0)
				(type default)
			)
			(fill no)
			(layer "B.CrtYd")
		)
		(fp_rect
			(start 0.508 0.9398)
			(end -0.508 -0.9398)
			(stroke
				(width 0)
				(type default)
			)
			(fill no)
			(layer "B.Fab")
		)
		(pad "1" smd custom
			(at 0 -0.4445 270)
			(size 0.1397 0.1397)
			(layers "B.Cu" "B.Mask" "B.Paste")
			(net "BMC0_SMB14_CLK")
			(options
				(clearance outline)
				(anchor circle)
			)
			(primitives
				(gr_poly
					(pts
						(arc
							(start -0.1778 0.2794)
							(mid -0.249642 0.249642)
							(end -0.2794 0.1778)
						)
						(arc
							(start -0.2794 -0.1778)
							(mid -0.249642 -0.249642)
							(end -0.1778 -0.2794)
						)
						(arc
							(start 0.1778 -0.2794)
							(mid 0.249642 -0.249642)
							(end 0.2794 -0.1778)
						)
						(arc
							(start 0.2794 0.1778)
							(mid 0.249642 0.249642)
							(end 0.1778 0.2794)
						)
					)
					(width 0)
					(fill yes)
				)
			)
		)
		(pad "2" smd custom
			(at 0 0.4445 270)
			(size 0.1397 0.1397)
			(layers "B.Cu" "B.Mask" "B.Paste")
			(net "BMC_I2C14_MINI8_SCL_S")
			(options
				(clearance outline)
				(anchor circle)
			)
			(primitives
				(gr_poly
					(pts
						(arc
							(start -0.1778 0.2794)
							(mid -0.249642 0.249642)
							(end -0.2794 0.1778)
						)
						(arc
							(start -0.2794 -0.1778)
							(mid -0.249642 -0.249642)
							(end -0.1778 -0.2794)
						)
						(arc
							(start 0.1778 -0.2794)
							(mid 0.249642 -0.249642)
							(end 0.2794 -0.1778)
						)
						(arc
							(start 0.2794 0.1778)
							(mid 0.249642 0.249642)
							(end 0.1778 0.2794)
						)
					)
					(width 0)
					(fill yes)
				)
			)
		)
	)
	(footprint ""
		(layer "B.Cu")
		(at 220.702124 -190.601092)
		(property "Reference" "R4135"
			(at 0 0 0)
			(layer "B.SilkS")
			(hide yes)
			(effects
				(font
					(size 1.27 1.27)
				)
				(justify mirror)
			)
		)
		(property "Value" "4K7R2F-GP"
			(at -0.064008 -3.993896 0)
			(unlocked yes)
			(layer "B.Fab")
			(hide yes)
			(effects
				(font
					(size 1.016 1.016)
					(thickness 0.1524)
				)
				(justify mirror)
			)
		)
		(property "Device Type" "R402H16"
			(at -0.064008 -5.517896 0)
			(unlocked yes)
			(layer "B.Fab")
			(hide yes)
			(effects
				(font
					(size 1.016 1.016)
					(thickness 0.1524)
				)
				(justify mirror)
			)
		)
		(duplicate_pad_numbers_are_jumpers no)
		(fp_line
			(start -0.508 -0.9398)
			(end 0.508 -0.9398)
			(stroke
				(width 0.1524)
				(type default)
			)
			(layer "B.SilkS")
		)
		(fp_line
			(start 0.508 -0.9398)
			(end 0.508 0.9398)
			(stroke
				(width 0.1524)
				(type default)
			)
			(layer "B.SilkS")
		)
		(fp_rect
			(start 0.508 0.9398)
			(end -0.508 -0.9398)
			(stroke
				(width 0)
				(type default)
			)
			(fill no)
			(layer "B.CrtYd")
		)
		(fp_rect
			(start 0.508 0.9398)
			(end -0.508 -0.9398)
			(stroke
				(width 0)
				(type default)
			)
			(fill no)
			(layer "B.Fab")
		)
		(pad "1" smd custom
			(at 0 -0.4445 180)
			(size 0.1397 0.1397)
			(layers "B.Cu" "B.Mask" "B.Paste")
			(net "SSD_ATNLED#3")
			(options
				(clearance outline)
				(anchor circle)
			)
			(primitives
				(gr_poly
					(pts
						(arc
							(start -0.1778 0.2794)
							(mid -0.249642 0.249642)
							(end -0.2794 0.1778)
						)
						(arc
							(start -0.2794 -0.1778)
							(mid -0.249642 -0.249642)
							(end -0.1778 -0.2794)
						)
						(arc
							(start 0.1778 -0.2794)
							(mid 0.249642 -0.249642)
							(end 0.2794 -0.1778)
						)
						(arc
							(start 0.2794 0.1778)
							(mid 0.249642 0.249642)
							(end 0.1778 0.2794)
						)
					)
					(width 0)
					(fill yes)
				)
			)
		)
		(pad "2" smd custom
			(at 0 0.4445 180)
			(size 0.1397 0.1397)
			(layers "B.Cu" "B.Mask" "B.Paste")
			(net "P3V3_STBY")
			(options
				(clearance outline)
				(anchor circle)
			)
			(primitives
				(gr_poly
					(pts
						(arc
							(start -0.1778 0.2794)
							(mid -0.249642 0.249642)
							(end -0.2794 0.1778)
						)
						(arc
							(start -0.2794 -0.1778)
							(mid -0.249642 -0.249642)
							(end -0.1778 -0.2794)
						)
						(arc
							(start 0.1778 -0.2794)
							(mid 0.249642 -0.249642)
							(end 0.2794 -0.1778)
						)
						(arc
							(start 0.2794 0.1778)
							(mid 0.249642 0.249642)
							(end 0.1778 0.2794)
						)
					)
					(width 0)
					(fill yes)
				)
			)
		)
	)
	(footprint ""
		(layer "B.Cu")
		(at 74.804524 -183.235092)
		(property "Reference" "R4104"
			(at 0 0 0)
			(layer "B.SilkS")
			(hide yes)
			(effects
				(font
					(size 1.27 1.27)
				)
				(justify mirror)
			)
		)
		(property "Value" "4K7R2F-GP"
			(at -0.064008 -3.993896 0)
			(unlocked yes)
			(layer "B.Fab")
			(hide yes)
			(effects
				(font
					(size 1.016 1.016)
					(thickness 0.1524)
				)
				(justify mirror)
			)
		)
		(property "Device Type" "R402H16"
			(at -0.064008 -5.517896 0)
			(unlocked yes)
			(layer "B.Fab")
			(hide yes)
			(effects
				(font
					(size 1.016 1.016)
					(thickness 0.1524)
				)
				(justify mirror)
			)
		)
		(duplicate_pad_numbers_are_jumpers no)
		(fp_line
			(start -0.508 -0.9398)
			(end 0.508 -0.9398)
			(stroke
				(width 0.1524)
				(type default)
			)
			(layer "B.SilkS")
		)
		(fp_line
			(start 0.508 -0.9398)
			(end 0.508 0.9398)
			(stroke
				(width 0.1524)
				(type default)
			)
			(layer "B.SilkS")
		)
		(fp_rect
			(start 0.508 0.9398)
			(end -0.508 -0.9398)
			(stroke
				(width 0)
				(type default)
			)
			(fill no)
			(layer "B.CrtYd")
		)
		(fp_rect
			(start 0.508 0.9398)
			(end -0.508 -0.9398)
			(stroke
				(width 0)
				(type default)
			)
			(fill no)
			(layer "B.Fab")
		)
		(pad "1" smd custom
			(at 0 -0.4445 180)
			(size 0.1397 0.1397)
			(layers "B.Cu" "B.Mask" "B.Paste")
			(net "SSD_PERST#0")
			(options
				(clearance outline)
				(anchor circle)
			)
			(primitives
				(gr_poly
					(pts
						(arc
							(start -0.1778 0.2794)
							(mid -0.249642 0.249642)
							(end -0.2794 0.1778)
						)
						(arc
							(start -0.2794 -0.1778)
							(mid -0.249642 -0.249642)
							(end -0.1778 -0.2794)
						)
						(arc
							(start 0.1778 -0.2794)
							(mid 0.249642 -0.249642)
							(end 0.2794 -0.1778)
						)
						(arc
							(start 0.2794 0.1778)
							(mid 0.249642 0.249642)
							(end 0.1778 0.2794)
						)
					)
					(width 0)
					(fill yes)
				)
			)
		)
		(pad "2" smd custom
			(at 0 0.4445 180)
			(size 0.1397 0.1397)
			(layers "B.Cu" "B.Mask" "B.Paste")
			(net "P3V3_STBY")
			(options
				(clearance outline)
				(anchor circle)
			)
			(primitives
				(gr_poly
					(pts
						(arc
							(start -0.1778 0.2794)
							(mid -0.249642 0.249642)
							(end -0.2794 0.1778)
						)
						(arc
							(start -0.2794 -0.1778)
							(mid -0.249642 -0.249642)
							(end -0.1778 -0.2794)
						)
						(arc
							(start 0.1778 -0.2794)
							(mid 0.249642 -0.249642)
							(end 0.2794 -0.1778)
						)
						(arc
							(start 0.2794 0.1778)
							(mid 0.249642 0.249642)
							(end 0.1778 0.2794)
						)
					)
					(width 0)
					(fill yes)
				)
			)
		)
	)
	(footprint ""
		(layer "B.Cu")
		(at 50.673 -195.58 180)
		(property "Reference" "R892"
			(at 0 0 0)
			(layer "B.SilkS")
			(hide yes)
			(effects
				(font
					(size 1.27 1.27)
				)
				(justify mirror)
			)
		)
		(property "Value" "0R2J-2-GP"
			(at -0.064008 -3.993896 180)
			(unlocked yes)
			(layer "B.Fab")
			(hide yes)
			(effects
				(font
					(size 1.016 1.016)
					(thickness 0.1524)
				)
				(justify mirror)
			)
		)
		(property "Device Type" "R402H16"
			(at -0.064008 -5.517896 180)
			(unlocked yes)
			(layer "B.Fab")
			(hide yes)
			(effects
				(font
					(size 1.016 1.016)
					(thickness 0.1524)
				)
				(justify mirror)
			)
		)
		(duplicate_pad_numbers_are_jumpers no)
		(fp_line
			(start 0.508 -0.9398)
			(end 0.508 0.9398)
			(stroke
				(width 0.1524)
				(type default)
			)
			(layer "B.SilkS")
		)
		(fp_line
			(start -0.508 -0.9398)
			(end 0.508 -0.9398)
			(stroke
				(width 0.1524)
				(type default)
			)
			(layer "B.SilkS")
		)
		(fp_rect
			(start 0.508 0.9398)
			(end -0.508 -0.9398)
			(stroke
				(width 0)
				(type default)
			)
			(fill no)
			(layer "B.CrtYd")
		)
		(fp_rect
			(start 0.508 0.9398)
			(end -0.508 -0.9398)
			(stroke
				(width 0)
				(type default)
			)
			(fill no)
			(layer "B.Fab")
		)
		(pad "1" smd custom
			(at 0 -0.4445)
			(size 0.1397 0.1397)
			(layers "B.Cu" "B.Mask" "B.Paste")
			(net "BMC_I2C7_B_DPB_SDA")
			(options
				(clearance outline)
				(anchor circle)
			)
			(primitives
				(gr_poly
					(pts
						(arc
							(start -0.1778 0.2794)
							(mid -0.249642 0.249642)
							(end -0.2794 0.1778)
						)
						(arc
							(start -0.2794 -0.1778)
							(mid -0.249642 -0.249642)
							(end -0.1778 -0.2794)
						)
						(arc
							(start 0.1778 -0.2794)
							(mid 0.249642 -0.249642)
							(end 0.2794 -0.1778)
						)
						(arc
							(start 0.2794 0.1778)
							(mid 0.249642 0.249642)
							(end 0.1778 0.2794)
						)
					)
					(width 0)
					(fill yes)
				)
			)
		)
		(pad "2" smd custom
			(at 0 0.4445)
			(size 0.1397 0.1397)
			(layers "B.Cu" "B.Mask" "B.Paste")
			(net "BUF_I2C7_B_DPB_SDA")
			(options
				(clearance outline)
				(anchor circle)
			)
			(primitives
				(gr_poly
					(pts
						(arc
							(start -0.1778 0.2794)
							(mid -0.249642 0.249642)
							(end -0.2794 0.1778)
						)
						(arc
							(start -0.2794 -0.1778)
							(mid -0.249642 -0.249642)
							(end -0.1778 -0.2794)
						)
						(arc
							(start 0.1778 -0.2794)
							(mid 0.249642 -0.249642)
							(end 0.2794 -0.1778)
						)
						(arc
							(start 0.2794 0.1778)
							(mid 0.249642 0.249642)
							(end 0.1778 0.2794)
						)
					)
					(width 0)
					(fill yes)
				)
			)
		)
	)
)
